# S9S_MB_2U (Grand Teton) — schematic netlist excerpt (pin names and nets, part order shuffled) for the footprints in the layout excerpt that follows; sources: Cadence DE-HDL packaged netlist, KiCad conversion of 03242023_DA0F0TMBIJ0_F0T_Motherboard_J_brd_V01_OCP.brd

R4413  Q_RES  33.2 1% CHIP  pkg 0402LF  page 123 : A = H_CPU0_MEMTRIP_VT_N ; B = H_CPU0_MEMTRIP_LVC1_N
C626  Q_CAP  1000PF 50V 5% EMPTY  pkg 0402  page 278 : A = PWRGD_PVCCD_HV_CPU0_R ; B = GND

(kicad_pcb
	(version 20260206)
	(generator "pcbnew")
	(generator_version "10.0")
	(general
		(thickness 1.6)
		(legacy_teardrops no)
	)
	(paper "A4")
	(title_block
		(title "03242023_DA0F0TMBIJ0_F0T_Motherboard_J_brd_V01_OCP.brd")
		(comment 1 "Grand Teton / footprints 2841-2842 of 6105")
	)
	(layers
		(0 "F.Cu" signal "TOP")
		(4 "In1.Cu" signal "GND")
		(6 "In2.Cu" signal "IN1")
		(8 "In3.Cu" signal "GND1")
		(10 "In4.Cu" signal "IN2")
		(12 "In5.Cu" signal "GND2")
		(14 "In6.Cu" signal "IN3")
		(16 "In7.Cu" signal "GND3")
		(18 "In8.Cu" signal "VCC")
		(20 "In9.Cu" signal "VCC1")
		(22 "In10.Cu" signal "GND4")
		(24 "In11.Cu" signal "IN4")
		(26 "In12.Cu" signal "GND5")
		(28 "In13.Cu" signal "IN5")
		(30 "In14.Cu" signal "GND6")
		(32 "In15.Cu" signal "IN6")
		(34 "In16.Cu" signal "GND7")
		(2 "B.Cu" signal "BOTTOM")
		(9 "F.Adhes" user "F.Adhesive")
		(11 "B.Adhes" user "B.Adhesive")
		(13 "F.Paste" user "Package Geometry/Pastemask Top")
		(15 "B.Paste" user "Package Geometry/Pastemask Bottom")
		(5 "F.SilkS" user "Ref Des/Silkscreen Top")
		(7 "B.SilkS" user "Ref Des/Silkscreen Bottom")
		(1 "F.Mask" user "Board Geometry/Soldermask Top")
		(3 "B.Mask" user "Board Geometry/Soldermask Bottom")
		(17 "Dwgs.User" user "User.Drawings")
		(19 "Cmts.User" user "User.Comments")
		(21 "Eco1.User" user "User.Eco1")
		(23 "Eco2.User" user "User.Eco2")
		(25 "Edge.Cuts" user "Board Geometry/Outline")
		(27 "Margin" user)
		(31 "F.CrtYd" user "Package Geometry/Place Bound Top")
		(29 "B.CrtYd" user "Package Geometry/Place Bound Bottom")
		(35 "F.Fab" user "Ref Des/Assembly Top")
		(33 "B.Fab" user "Ref Des/Assembly Bottom")
	)
	(footprint ""
		(layer "F.Cu")
		(at 131.50088 -100.167948 -90)
		(property "Reference" "R4413"
			(at 0 0 270)
			(layer "F.SilkS")
			(hide yes)
			(effects
				(font
					(size 1.27 1.27)
				)
			)
		)
		(property "Value" ""
			(at 0 0 270)
			(layer "F.Fab")
			(effects
				(font
					(size 1.27 1.27)
				)
			)
		)
		(duplicate_pad_numbers_are_jumpers no)
		(fp_line
			(start -0.7874 0.4064)
			(end -0.7874 -0.4064)
			(stroke
				(width 0.1524)
				(type default)
			)
			(layer "F.SilkS")
		)
		(fp_line
			(start 0.7874 0.4064)
			(end -0.7874 0.4064)
			(stroke
				(width 0.1524)
				(type default)
			)
			(layer "F.SilkS")
		)
		(fp_line
			(start -0.7874 -0.4064)
			(end 0.7874 -0.4064)
			(stroke
				(width 0.1524)
				(type default)
			)
			(layer "F.SilkS")
		)
		(fp_line
			(start 0.7874 -0.4064)
			(end 0.7874 0.4064)
			(stroke
				(width 0.1524)
				(type default)
			)
			(layer "F.SilkS")
		)
		(fp_line
			(start -0.67945 0.3048)
			(end -0.67945 -0.305054)
			(stroke
				(width 0.1)
				(type default)
			)
			(layer "F.Fab")
		)
		(fp_line
			(start -0.12065 0.3048)
			(end -0.67945 0.3048)
			(stroke
				(width 0.1)
				(type default)
			)
			(layer "F.Fab")
		)
		(fp_line
			(start 0.120396 0.3048)
			(end 0.120396 0.2794)
			(stroke
				(width 0.1)
				(type default)
			)
			(layer "F.Fab")
		)
		(fp_line
			(start 0.67945 0.3048)
			(end 0.120396 0.3048)
			(stroke
				(width 0.1)
				(type default)
			)
			(layer "F.Fab")
		)
		(fp_line
			(start -0.12065 0.2794)
			(end -0.12065 0.3048)
			(stroke
				(width 0.1)
				(type default)
			)
			(layer "F.Fab")
		)
		(fp_line
			(start 0.120396 0.2794)
			(end -0.12065 0.2794)
			(stroke
				(width 0.1)
				(type default)
			)
			(layer "F.Fab")
		)
		(fp_line
			(start -0.12065 -0.2794)
			(end 0.12065 -0.2794)
			(stroke
				(width 0.1)
				(type default)
			)
			(layer "F.Fab")
		)
		(fp_line
			(start 0.12065 -0.2794)
			(end 0.12065 -0.3048)
			(stroke
				(width 0.1)
				(type default)
			)
			(layer "F.Fab")
		)
		(fp_line
			(start 0.12065 -0.3048)
			(end 0.67945 -0.3048)
			(stroke
				(width 0.1)
				(type default)
			)
			(layer "F.Fab")
		)
		(fp_line
			(start 0.67945 -0.3048)
			(end 0.67945 0.3048)
			(stroke
				(width 0.1)
				(type default)
			)
			(layer "F.Fab")
		)
		(fp_line
			(start -0.67945 -0.305054)
			(end -0.12065 -0.305054)
			(stroke
				(width 0.1)
				(type default)
			)
			(layer "F.Fab")
		)
		(fp_line
			(start -0.12065 -0.305054)
			(end -0.12065 -0.2794)
			(stroke
				(width 0.1)
				(type default)
			)
			(layer "F.Fab")
		)
		(pad "1" smd circle
			(at -0.40005 0 270)
			(size 0 0)
			(layers "F.Cu" "F.Mask" "F.Paste")
			(net "H_CPU0_MEMTRIP_VT_N")
		)
		(pad "2" smd circle
			(at 0.40005 0 270)
			(size 0 0)
			(layers "F.Cu" "F.Mask" "F.Paste")
			(net "H_CPU0_MEMTRIP_LVC1_N")
		)
	)
	(footprint ""
		(layer "F.Cu")
		(at 437.242966 -120.614186)
		(property "Reference" "C626"
			(at 0 0 0)
			(layer "F.SilkS")
			(hide yes)
			(effects
				(font
					(size 1.27 1.27)
				)
			)
		)
		(property "Value" ""
			(at 0 0 0)
			(layer "F.Fab")
			(effects
				(font
					(size 1.27 1.27)
				)
			)
		)
		(duplicate_pad_numbers_are_jumpers no)
		(fp_line
			(start -0.7874 -0.4064)
			(end 0.7874 -0.4064)
			(stroke
				(width 0.1524)
				(type default)
			)
			(layer "F.SilkS")
		)
		(fp_line
			(start -0.7874 0.4064)
			(end -0.7874 -0.4064)
			(stroke
				(width 0.1524)
				(type default)
			)
			(layer "F.SilkS")
		)
		(fp_line
			(start 0.7874 -0.4064)
			(end 0.7874 0.4064)
			(stroke
				(width 0.1524)
				(type default)
			)
			(layer "F.SilkS")
		)
		(fp_line
			(start 0.7874 0.4064)
			(end -0.7874 0.4064)
			(stroke
				(width 0.1524)
				(type default)
			)
			(layer "F.SilkS")
		)
		(fp_line
			(start -0.67945 -0.305054)
			(end -0.12065 -0.305054)
			(stroke
				(width 0.1)
				(type default)
			)
			(layer "F.Fab")
		)
		(fp_line
			(start -0.67945 0.3048)
			(end -0.67945 -0.305054)
			(stroke
				(width 0.1)
				(type default)
			)
			(layer "F.Fab")
		)
		(fp_line
			(start -0.12065 -0.305054)
			(end -0.12065 -0.2794)
			(stroke
				(width 0.1)
				(type default)
			)
			(layer "F.Fab")
		)
		(fp_line
			(start -0.12065 -0.2794)
			(end 0.12065 -0.2794)
			(stroke
				(width 0.1)
				(type default)
			)
			(layer "F.Fab")
		)
		(fp_line
			(start -0.12065 0.2794)
			(end -0.12065 0.3048)
			(stroke
				(width 0.1)
				(type default)
			)
			(layer "F.Fab")
		)
		(fp_line
			(start -0.12065 0.3048)
			(end -0.67945 0.3048)
			(stroke
				(width 0.1)
				(type default)
			)
			(layer "F.Fab")
		)
		(fp_line
			(start 0.120396 0.2794)
			(end -0.12065 0.2794)
			(stroke
				(width 0.1)
				(type default)
			)
			(layer "F.Fab")
		)
		(fp_line
			(start 0.120396 0.3048)
			(end 0.120396 0.2794)
			(stroke
				(width 0.1)
				(type default)
			)
			(layer "F.Fab")
		)
		(fp_line
			(start 0.12065 -0.3048)
			(end 0.67945 -0.3048)
			(stroke
				(width 0.1)
				(type default)
			)
			(layer "F.Fab")
		)
		(fp_line
			(start 0.12065 -0.2794)
			(end 0.12065 -0.3048)
			(stroke
				(width 0.1)
				(type default)
			)
			(layer "F.Fab")
		)
		(fp_line
			(start 0.67945 -0.3048)
			(end 0.67945 0.3048)
			(stroke
				(width 0.1)
				(type default)
			)
			(layer "F.Fab")
		)
		(fp_line
			(start 0.67945 0.3048)
			(end 0.120396 0.3048)
			(stroke
				(width 0.1)
				(type default)
			)
			(layer "F.Fab")
		)
		(pad "1" smd circle
			(at -0.40005 0)
			(size 0 0)
			(layers "F.Cu" "F.Mask" "F.Paste")
			(net "PWRGD_PVCCD_HV_CPU0_R")
		)
		(pad "2" smd circle
			(at 0.40005 0)
			(size 0 0)
			(layers "F.Cu" "F.Mask" "F.Paste")
			(net "GND")
		)
	)
)
